# S9S_MB_2U (Grand Teton) — schematic netlist excerpt (pin names and nets, part order shuffled) for the footprints in the layout excerpt that follows; sources: Cadence DE-HDL packaged netlist, KiCad conversion of 03242023_DA0F0TMBIJ0_F0T_Motherboard_J_brd_V01_OCP.brd

PU76_P1_2  ISL99390FRZTR5935  ISL99390FRZ-TR5935 IC  pkg QFN21_6X5XB  page 289
  VOS  = PVCCFA_EHV_FIVRA_CPU1_VOS2
  AGND  = GND
  VCC  = PVCCFA_EHV_FIVRA_CPU1_VDD2
  PVCC  = PVCCFA_EHV_FIVRA_CPU1_PVCC2
  PGND1  = GND
  GL1  = NC
  PGND2  = GND
  SW  = SW_PVCCFA_EHV_FIVRA_CPU1_SW2
  VIN1  = SW_P12V_PVCCFA_EHV_FIVRA_CPU1_L
  VIN2  = SW_P12V_PVCCFA_EHV_FIVRA_CPU1_L
  DNC  = NC
  PHASE  = SW_PVCCFA_EHV_FIVRA_CPU1_BOOTR2
  BOOT  = SW_PVCCFA_EHV_FIVRA_CPU1_BOOT2
  PWM  = PVCCFA_EHV_FIVRA_CPU1_PWM2
  EN  = PVCCFA_EHV_FIVRA_CPU1_VDD2
  TOUT_FLT  = PVCCFA_EHV_FIVRA_CPU1_BTSEN
  LSET  = PVCCFA_EHV_FIVRA_CPU1_LSET2
  IOUT  = PVCCFA_EHV_FIVRA_CPU1_IMON2
  REFIN  = PVCCIN_CPU1_VREF
  PGND3  = GND
  GL2  = NC

(kicad_pcb
	(version 20260206)
	(generator "pcbnew")
	(generator_version "10.0")
	(general
		(thickness 1.6)
		(legacy_teardrops no)
	)
	(paper "A4")
	(title_block
		(title "03242023_DA0F0TMBIJ0_F0T_Motherboard_J_brd_V01_OCP.brd")
		(comment 1 "Grand Teton / footprints 18-18 of 6105")
	)
	(layers
		(0 "F.Cu" signal "TOP")
		(4 "In1.Cu" signal "GND")
		(6 "In2.Cu" signal "IN1")
		(8 "In3.Cu" signal "GND1")
		(10 "In4.Cu" signal "IN2")
		(12 "In5.Cu" signal "GND2")
		(14 "In6.Cu" signal "IN3")
		(16 "In7.Cu" signal "GND3")
		(18 "In8.Cu" signal "VCC")
		(20 "In9.Cu" signal "VCC1")
		(22 "In10.Cu" signal "GND4")
		(24 "In11.Cu" signal "IN4")
		(26 "In12.Cu" signal "GND5")
		(28 "In13.Cu" signal "IN5")
		(30 "In14.Cu" signal "GND6")
		(32 "In15.Cu" signal "IN6")
		(34 "In16.Cu" signal "GND7")
		(2 "B.Cu" signal "BOTTOM")
		(9 "F.Adhes" user "F.Adhesive")
		(11 "B.Adhes" user "B.Adhesive")
		(13 "F.Paste" user "Package Geometry/Pastemask Top")
		(15 "B.Paste" user "Package Geometry/Pastemask Bottom")
		(5 "F.SilkS" user "Ref Des/Silkscreen Top")
		(7 "B.SilkS" user "Ref Des/Silkscreen Bottom")
		(1 "F.Mask" user "Board Geometry/Soldermask Top")
		(3 "B.Mask" user "Board Geometry/Soldermask Bottom")
		(17 "Dwgs.User" user "User.Drawings")
		(19 "Cmts.User" user "User.Comments")
		(21 "Eco1.User" user "User.Eco1")
		(23 "Eco2.User" user "User.Eco2")
		(25 "Edge.Cuts" user "Board Geometry/Outline")
		(27 "Margin" user)
		(31 "F.CrtYd" user "Package Geometry/Place Bound Top")
		(29 "B.CrtYd" user "Package Geometry/Place Bound Bottom")
		(35 "F.Fab" user "Ref Des/Assembly Top")
		(33 "B.Fab" user "Ref Des/Assembly Bottom")
	)
	(footprint ""
		(layer "F.Cu")
		(at 51.25339 -353.547934)
		(property "Reference" "PU76_P1_2"
			(at 6.21411 -1.416304 0)
			(unlocked yes)
			(layer "F.SilkS")
			(effects
				(font
					(size 0.7874 0.5842)
					(thickness 0.1524)
				)
				(justify left)
			)
		)
		(property "Value" ""
			(at 0 0 0)
			(layer "F.Fab")
			(effects
				(font
					(size 1.27 1.27)
				)
			)
		)
		(duplicate_pad_numbers_are_jumpers no)
		(fp_line
			(start -2.500122 -2.999994)
			(end -2.24409 -2.999994)
			(stroke
				(width 0.1524)
				(type default)
			)
			(layer "F.SilkS")
		)
		(fp_line
			(start -2.500122 -2.529078)
			(end -2.500122 -2.999994)
			(stroke
				(width 0.1524)
				(type default)
			)
			(layer "F.SilkS")
		)
		(fp_line
			(start -2.500122 0.6604)
			(end -2.500122 0.229108)
			(stroke
				(width 0.1524)
				(type default)
			)
			(layer "F.SilkS")
		)
		(fp_line
			(start -2.500122 2.999994)
			(end -2.500122 2.339594)
			(stroke
				(width 0.1524)
				(type default)
			)
			(layer "F.SilkS")
		)
		(fp_line
			(start -2.2987 2.999994)
			(end -2.500122 2.999994)
			(stroke
				(width 0.1524)
				(type default)
			)
			(layer "F.SilkS")
		)
		(fp_line
			(start 2.31394 -2.999994)
			(end 2.500122 -2.999994)
			(stroke
				(width 0.1524)
				(type default)
			)
			(layer "F.SilkS")
		)
		(fp_line
			(start 2.500122 -2.999994)
			(end 2.500122 -2.44348)
			(stroke
				(width 0.1524)
				(type default)
			)
			(layer "F.SilkS")
		)
		(fp_line
			(start 2.500122 2.339594)
			(end 2.500122 2.999994)
			(stroke
				(width 0.1524)
				(type default)
			)
			(layer "F.SilkS")
		)
		(fp_line
			(start 2.500122 2.999994)
			(end 2.2987 2.999994)
			(stroke
				(width 0.1524)
				(type default)
			)
			(layer "F.SilkS")
		)
		(fp_poly
			(pts
				(xy -5.285232 -2.866898) (xy -4.269232 -2.358898) (xy -5.285232 -1.850898)
			)
			(stroke
				(width 0)
				(type default)
			)
			(fill yes)
			(layer "F.SilkS")
		)
		(fp_line
			(start -2.500122 -2.999994)
			(end 2.500122 -2.999994)
			(stroke
				(width 0.1)
				(type default)
			)
			(layer "F.Fab")
		)
		(fp_line
			(start -2.500122 2.999994)
			(end -2.500122 -2.999994)
			(stroke
				(width 0.1)
				(type default)
			)
			(layer "F.Fab")
		)
		(fp_line
			(start 2.500122 -2.999994)
			(end 2.500122 2.999994)
			(stroke
				(width 0.1)
				(type default)
			)
			(layer "F.Fab")
		)
		(fp_line
			(start 2.500122 2.999994)
			(end -2.500122 2.999994)
			(stroke
				(width 0.1)
				(type default)
			)
			(layer "F.Fab")
		)
		(fp_poly
			(pts
				(xy -4.218432 -2.783078) (xy -4.218432 -1.767078) (xy -3.202432 -2.275078)
			)
			(stroke
				(width 0)
				(type default)
			)
			(fill yes)
			(layer "F.Fab")
		)
		(pad "1" smd rect
			(at -2.400046 -2.275078 90)
			(size 0.2286 0.6096)
			(layers "F.Cu" "F.Mask" "F.Paste")
			(net "PVCCFA_EHV_FIVRA_CPU1_VOS2")
		)
		(pad "2" smd rect
			(at -2.400046 -1.82499 90)
			(size 0.2286 0.6096)
			(layers "F.Cu" "F.Mask" "F.Paste")
			(net "GND")
		)
		(pad "3" smd rect
			(at -2.400046 -1.374902 90)
			(size 0.2286 0.6096)
			(layers "F.Cu" "F.Mask" "F.Paste")
			(net "PVCCFA_EHV_FIVRA_CPU1_VDD2")
		)
		(pad "4" smd rect
			(at -2.400046 -0.925068 90)
			(size 0.2286 0.6096)
			(layers "F.Cu" "F.Mask" "F.Paste")
			(net "PVCCFA_EHV_FIVRA_CPU1_PVCC2")
		)
		(pad "5" smd rect
			(at -2.400046 -0.47498 90)
			(size 0.2286 0.6096)
			(layers "F.Cu" "F.Mask" "F.Paste")
			(net "GND")
		)
		(pad "6" smd rect
			(at -2.400046 -0.024892 90)
			(size 0.2286 0.6096)
			(layers "F.Cu" "F.Mask" "F.Paste")
			(net "Net_8502")
		)
		(pad "7_9-20_24" smd circle
			(at 0 1.150112 90)
			(size 0 0)
			(layers "F.Cu" "F.Mask" "F.Paste")
			(net "GND")
		)
		(pad "10_19" smd rect
			(at 0 2.899918 90)
			(size 0.6096 4.318)
			(layers "F.Cu" "F.Mask" "F.Paste")
			(net "SW_PVCCFA_EHV_FIVRA_CPU1_SW2")
		)
		(pad "25_29" smd rect
			(at 1.549908 -1.279906 270)
			(size 2.0574 2.3114)
			(layers "F.Cu" "F.Mask" "F.Paste")
			(net "SW_P12V_PVCCFA_EHV_FIVRA_CPU1_L")
		)
		(pad "30" smd rect
			(at 2.05994 -2.899918)
			(size 0.2286 0.6096)
			(layers "F.Cu" "F.Mask" "F.Paste")
			(net "SW_P12V_PVCCFA_EHV_FIVRA_CPU1_L")
		)
		(pad "31" smd rect
			(at 1.610106 -2.899918)
			(size 0.2286 0.6096)
			(layers "F.Cu" "F.Mask" "F.Paste")
			(net "Net_8503")
		)
		(pad "32" smd rect
			(at 1.160018 -2.899918)
			(size 0.2286 0.6096)
			(layers "F.Cu" "F.Mask" "F.Paste")
			(net "SW_PVCCFA_EHV_FIVRA_CPU1_BOOTR2")
		)
		(pad "33" smd rect
			(at 0.70993 -2.899918)
			(size 0.2286 0.6096)
			(layers "F.Cu" "F.Mask" "F.Paste")
			(net "SW_PVCCFA_EHV_FIVRA_CPU1_BOOT2")
		)
		(pad "34" smd rect
			(at 0.260096 -2.899918)
			(size 0.2286 0.6096)
			(layers "F.Cu" "F.Mask" "F.Paste")
			(net "PVCCFA_EHV_FIVRA_CPU1_PWM2")
		)
		(pad "35" smd rect
			(at -0.189992 -2.899918)
			(size 0.2286 0.6096)
			(layers "F.Cu" "F.Mask" "F.Paste")
			(net "PVCCFA_EHV_FIVRA_CPU1_VDD2")
		)
		(pad "36" smd rect
			(at -0.64008 -2.899918)
			(size 0.2286 0.6096)
			(layers "F.Cu" "F.Mask" "F.Paste")
			(net "PVCCFA_EHV_FIVRA_CPU1_BTSEN")
		)
		(pad "37" smd rect
			(at -1.089914 -2.899918)
			(size 0.2286 0.6096)
			(layers "F.Cu" "F.Mask" "F.Paste")
			(net "PVCCFA_EHV_FIVRA_CPU1_LSET2")
		)
		(pad "38" smd rect
			(at -1.540002 -2.899918)
			(size 0.2286 0.6096)
			(layers "F.Cu" "F.Mask" "F.Paste")
			(net "PVCCFA_EHV_FIVRA_CPU1_IMON2")
		)
		(pad "39" smd rect
			(at -1.99009 -2.899918)
			(size 0.2286 0.6096)
			(layers "F.Cu" "F.Mask" "F.Paste")
			(net "PVCCIN_CPU1_VREF")
		)
		(pad "40" smd rect
			(at -0.87503 -1.27508)
			(size 1.7526 1.9558)
			(layers "F.Cu" "F.Mask" "F.Paste")
			(net "GND")
		)
		(pad "41" smd rect
			(at -1.525016 0.249936 270)
			(size 0.3048 0.4572)
			(layers "F.Cu" "F.Mask" "F.Paste")
			(net "Net_8501")
		)
		(zone
			(layer "F.Cu")
			(hatch none 0.5)
			(connect_pads
				(clearance 0)
			)
			(min_thickness 0.25)
			(keepout
				(tracks not_allowed)
				(vias allowed)
				(pads allowed)
				(copperpour not_allowed)
				(footprints allowed)
			)
			(placement
				(enabled no)
				(sheetname "")
			)
			(fill
				(thermal_gap 0.5)
				(thermal_bridge_width 0.5)
				(island_removal_mode 0)
			)
			(polygon
				(pts
					(xy 48.753268 -350.54794) (xy 48.753268 -351.262188) (xy 53.753512 -351.262188) (xy 53.753512 -350.54794)
					(xy 53.46319 -350.54794) (xy 53.46319 -351.003616) (xy 49.04359 -351.003616) (xy 49.04359 -350.54794)
				)
			)
		)
		(zone
			(layer "F.Cu")
			(hatch none 0.5)
			(connect_pads
				(clearance 0)
			)
			(min_thickness 0.25)
			(keepout
				(tracks not_allowed)
				(vias allowed)
				(pads allowed)
				(copperpour not_allowed)
				(footprints allowed)
			)
			(placement
				(enabled no)
				(sheetname "")
			)
			(fill
				(thermal_gap 0.5)
				(thermal_bridge_width 0.5)
				(island_removal_mode 0)
			)
			(polygon
				(pts
					(xy 49.5046 -353.794314) (xy 50.27676 -353.794314) (xy 50.27676 -353.466908) (xy 50.302668 -353.466908)
					(xy 50.302668 -352.844862) (xy 50.25644 -352.798634) (xy 48.753268 -352.798634) (xy 48.753268 -353.255326)
					(xy 49.448974 -353.255326) (xy 49.448974 -353.094798) (xy 50.007774 -353.094798) (xy 50.007774 -353.501198)
					(xy 49.448974 -353.501198) (xy 49.448974 -353.280726) (xy 48.753268 -353.280726) (xy 48.753268 -353.407726)
					(xy 49.208944 -353.407726) (xy 49.208944 -353.774248) (xy 49.5046 -353.774248)
				)
			)
		)
	)
)
